# SCM (Grand Teton) — schematic netlist excerpt (pin names and nets, part order shuffled) for the footprints in the layout excerpt that follows; sources: Cadence DE-HDL packaged netlist, KiCad conversion of 12092022_DA0F0TMDCD0_F0T_Management_Board_D_brd_V3_OCP.brd

R463  Q_RES  0 5% EMPTY  pkg 0402LF  page 35 : A = AC_PWR_BTN_R1_N ; B = AC_PWR_BTN_R2_N
R668  Q_RES  0 5% CHIP  pkg 0402LF  page 29 : A = USB3_01_MUX_FB_RXN ; B = USB3_01_FB_RXN
C327  Q_CAP  47UF 6.3V 20% X6S  pkg C1206  page 29 : A = P5V_USB_REAR ; B = GND

(kicad_pcb
	(version 20260206)
	(generator "pcbnew")
	(generator_version "10.0")
	(general
		(thickness 1.6)
		(legacy_teardrops no)
	)
	(paper "A4")
	(title_block
		(title "12092022_DA0F0TMDCD0_F0T_Management_Board_D_brd_V3_OCP.brd")
		(comment 1 "Grand Teton / footprints 153-155 of 1440")
	)
	(layers
		(0 "F.Cu" signal "TOP")
		(4 "In1.Cu" signal "GND")
		(6 "In2.Cu" signal "IN1")
		(8 "In3.Cu" signal "GND1")
		(10 "In4.Cu" signal "IN2")
		(12 "In5.Cu" signal "VCC")
		(14 "In6.Cu" signal "VCC1")
		(16 "In7.Cu" signal "IN3")
		(18 "In8.Cu" signal "GND2")
		(20 "In9.Cu" signal "IN4")
		(22 "In10.Cu" signal "GND3")
		(2 "B.Cu" signal "BOTTOM")
		(9 "F.Adhes" user "F.Adhesive")
		(11 "B.Adhes" user "B.Adhesive")
		(13 "F.Paste" user "Package Geometry/Pastemask Top")
		(15 "B.Paste" user "Package Geometry/Pastemask Bottom")
		(5 "F.SilkS" user "Ref Des/Silkscreen Top")
		(7 "B.SilkS" user "Ref Des/Silkscreen Bottom")
		(1 "F.Mask" user "Board Geometry/Soldermask Top")
		(3 "B.Mask" user "Board Geometry/Soldermask Bottom")
		(17 "Dwgs.User" user "User.Drawings")
		(19 "Cmts.User" user "User.Comments")
		(21 "Eco1.User" user "User.Eco1")
		(23 "Eco2.User" user "User.Eco2")
		(25 "Edge.Cuts" user "Board Geometry/Outline")
		(27 "Margin" user)
		(31 "F.CrtYd" user "Package Geometry/Place Bound Top")
		(29 "B.CrtYd" user "Package Geometry/Place Bound Bottom")
		(35 "F.Fab" user "Ref Des/Assembly Top")
		(33 "B.Fab" user "Ref Des/Assembly Bottom")
	)
	(footprint ""
		(layer "F.Cu")
		(at 43.966638 -22.15642 -90)
		(property "Reference" "R668"
			(at 0 0 270)
			(layer "F.SilkS")
			(hide yes)
			(effects
				(font
					(size 1.27 1.27)
				)
			)
		)
		(property "Value" ""
			(at 0 0 270)
			(layer "F.Fab")
			(effects
				(font
					(size 1.27 1.27)
				)
			)
		)
		(duplicate_pad_numbers_are_jumpers no)
		(fp_line
			(start 0.7874 0.4064)
			(end -0.7874 0.4064)
			(stroke
				(width 0.1524)
				(type default)
			)
			(layer "F.SilkS")
		)
		(fp_line
			(start -0.7874 -0.4064)
			(end 0.7874 -0.4064)
			(stroke
				(width 0.1524)
				(type default)
			)
			(layer "F.SilkS")
		)
		(fp_line
			(start -0.67945 0.3048)
			(end -0.67945 -0.305054)
			(stroke
				(width 0.1)
				(type default)
			)
			(layer "F.Fab")
		)
		(fp_line
			(start -0.12065 0.3048)
			(end -0.67945 0.3048)
			(stroke
				(width 0.1)
				(type default)
			)
			(layer "F.Fab")
		)
		(fp_line
			(start 0.120396 0.3048)
			(end 0.120396 0.2794)
			(stroke
				(width 0.1)
				(type default)
			)
			(layer "F.Fab")
		)
		(fp_line
			(start 0.67945 0.3048)
			(end 0.120396 0.3048)
			(stroke
				(width 0.1)
				(type default)
			)
			(layer "F.Fab")
		)
		(fp_line
			(start -0.12065 0.2794)
			(end -0.12065 0.3048)
			(stroke
				(width 0.1)
				(type default)
			)
			(layer "F.Fab")
		)
		(fp_line
			(start 0.120396 0.2794)
			(end -0.12065 0.2794)
			(stroke
				(width 0.1)
				(type default)
			)
			(layer "F.Fab")
		)
		(fp_line
			(start -0.12065 -0.2794)
			(end 0.12065 -0.2794)
			(stroke
				(width 0.1)
				(type default)
			)
			(layer "F.Fab")
		)
		(fp_line
			(start 0.12065 -0.2794)
			(end 0.12065 -0.3048)
			(stroke
				(width 0.1)
				(type default)
			)
			(layer "F.Fab")
		)
		(fp_line
			(start 0.12065 -0.3048)
			(end 0.67945 -0.3048)
			(stroke
				(width 0.1)
				(type default)
			)
			(layer "F.Fab")
		)
		(fp_line
			(start 0.67945 -0.3048)
			(end 0.67945 0.3048)
			(stroke
				(width 0.1)
				(type default)
			)
			(layer "F.Fab")
		)
		(fp_line
			(start -0.67945 -0.305054)
			(end -0.12065 -0.305054)
			(stroke
				(width 0.1)
				(type default)
			)
			(layer "F.Fab")
		)
		(fp_line
			(start -0.12065 -0.305054)
			(end -0.12065 -0.2794)
			(stroke
				(width 0.1)
				(type default)
			)
			(layer "F.Fab")
		)
		(pad "1" smd circle
			(at -0.40005 0 270)
			(size 0 0)
			(layers "F.Cu" "F.Mask" "F.Paste")
			(net "USB3_01_MUX_FB_RXN")
		)
		(pad "2" smd circle
			(at 0.40005 0 270)
			(size 0 0)
			(layers "F.Cu" "F.Mask" "F.Paste")
			(net "USB3_01_FB_RXN")
		)
	)
	(footprint ""
		(layer "F.Cu")
		(at 12.4206 -101.9429)
		(property "Reference" "R463"
			(at 0 0 0)
			(layer "F.SilkS")
			(hide yes)
			(effects
				(font
					(size 1.27 1.27)
				)
			)
		)
		(property "Value" ""
			(at 0 0 0)
			(layer "F.Fab")
			(effects
				(font
					(size 1.27 1.27)
				)
			)
		)
		(duplicate_pad_numbers_are_jumpers no)
		(fp_line
			(start -0.7874 -0.4064)
			(end 0.7874 -0.4064)
			(stroke
				(width 0.1524)
				(type default)
			)
			(layer "F.SilkS")
		)
		(fp_line
			(start -0.7874 0.4064)
			(end -0.7874 -0.4064)
			(stroke
				(width 0.1524)
				(type default)
			)
			(layer "F.SilkS")
		)
		(fp_line
			(start 0.7874 -0.4064)
			(end 0.7874 0.4064)
			(stroke
				(width 0.1524)
				(type default)
			)
			(layer "F.SilkS")
		)
		(fp_line
			(start 0.7874 0.4064)
			(end -0.7874 0.4064)
			(stroke
				(width 0.1524)
				(type default)
			)
			(layer "F.SilkS")
		)
		(fp_line
			(start -0.67945 -0.305054)
			(end -0.12065 -0.305054)
			(stroke
				(width 0.1)
				(type default)
			)
			(layer "F.Fab")
		)
		(fp_line
			(start -0.67945 0.3048)
			(end -0.67945 -0.305054)
			(stroke
				(width 0.1)
				(type default)
			)
			(layer "F.Fab")
		)
		(fp_line
			(start -0.12065 -0.305054)
			(end -0.12065 -0.2794)
			(stroke
				(width 0.1)
				(type default)
			)
			(layer "F.Fab")
		)
		(fp_line
			(start -0.12065 -0.2794)
			(end 0.12065 -0.2794)
			(stroke
				(width 0.1)
				(type default)
			)
			(layer "F.Fab")
		)
		(fp_line
			(start -0.12065 0.2794)
			(end -0.12065 0.3048)
			(stroke
				(width 0.1)
				(type default)
			)
			(layer "F.Fab")
		)
		(fp_line
			(start -0.12065 0.3048)
			(end -0.67945 0.3048)
			(stroke
				(width 0.1)
				(type default)
			)
			(layer "F.Fab")
		)
		(fp_line
			(start 0.120396 0.2794)
			(end -0.12065 0.2794)
			(stroke
				(width 0.1)
				(type default)
			)
			(layer "F.Fab")
		)
		(fp_line
			(start 0.120396 0.3048)
			(end 0.120396 0.2794)
			(stroke
				(width 0.1)
				(type default)
			)
			(layer "F.Fab")
		)
		(fp_line
			(start 0.12065 -0.3048)
			(end 0.67945 -0.3048)
			(stroke
				(width 0.1)
				(type default)
			)
			(layer "F.Fab")
		)
		(fp_line
			(start 0.12065 -0.2794)
			(end 0.12065 -0.3048)
			(stroke
				(width 0.1)
				(type default)
			)
			(layer "F.Fab")
		)
		(fp_line
			(start 0.67945 -0.3048)
			(end 0.67945 0.3048)
			(stroke
				(width 0.1)
				(type default)
			)
			(layer "F.Fab")
		)
		(fp_line
			(start 0.67945 0.3048)
			(end 0.120396 0.3048)
			(stroke
				(width 0.1)
				(type default)
			)
			(layer "F.Fab")
		)
		(pad "1" smd circle
			(at -0.40005 0)
			(size 0 0)
			(layers "F.Cu" "F.Mask" "F.Paste")
			(net "AC_PWR_BTN_R1_N")
		)
		(pad "2" smd circle
			(at 0.40005 0)
			(size 0 0)
			(layers "F.Cu" "F.Mask" "F.Paste")
			(net "AC_PWR_BTN_R2_N")
		)
	)
	(footprint ""
		(layer "F.Cu")
		(at 51.562 -18.034)
		(property "Reference" "C327"
			(at 0 0 0)
			(layer "F.SilkS")
			(hide yes)
			(effects
				(font
					(size 1.27 1.27)
				)
			)
		)
		(property "Value" ""
			(at 0 0 0)
			(layer "F.Fab")
			(effects
				(font
					(size 1.27 1.27)
				)
			)
		)
		(duplicate_pad_numbers_are_jumpers no)
		(fp_line
			(start -2.2098 -0.9398)
			(end 2.2098 -0.9398)
			(stroke
				(width 0.1524)
				(type default)
			)
			(layer "F.SilkS")
		)
		(fp_line
			(start -2.2098 0.9398)
			(end -2.2098 -0.9398)
			(stroke
				(width 0.1524)
				(type default)
			)
			(layer "F.SilkS")
		)
		(fp_line
			(start 2.2098 -0.9398)
			(end 2.2098 0.9398)
			(stroke
				(width 0.1524)
				(type default)
			)
			(layer "F.SilkS")
		)
		(fp_line
			(start 2.2098 0.9398)
			(end -2.2098 0.9398)
			(stroke
				(width 0.1524)
				(type default)
			)
			(layer "F.SilkS")
		)
		(fp_line
			(start -1.700022 -0.899922)
			(end 1.700022 -0.899922)
			(stroke
				(width 0.1)
				(type default)
			)
			(layer "F.Fab")
		)
		(fp_line
			(start -1.700022 0.899922)
			(end -1.700022 -0.899922)
			(stroke
				(width 0.1)
				(type default)
			)
			(layer "F.Fab")
		)
		(fp_line
			(start 1.700022 -0.899922)
			(end 1.700022 0.899922)
			(stroke
				(width 0.1)
				(type default)
			)
			(layer "F.Fab")
		)
		(fp_line
			(start 1.700022 0.899922)
			(end -1.700022 0.899922)
			(stroke
				(width 0.1)
				(type default)
			)
			(layer "F.Fab")
		)
		(pad "1" smd rect
			(at -1.4732 0 180)
			(size 1.1684 1.5748)
			(layers "F.Cu" "F.Mask" "F.Paste")
			(net "P5V_USB_REAR")
		)
		(pad "2" smd rect
			(at 1.4732 0 180)
			(size 1.1684 1.5748)
			(layers "F.Cu" "F.Mask" "F.Paste")
			(net "GND")
		)
	)
)
